# BASEBOARD_FAB2 (Tioga Pass) — schematic netlist excerpt (pin names and nets, part order shuffled) for the footprints in the layout excerpt that follows; sources: Cadence DE-HDL packaged netlist, KiCad conversion of Wiwynn_Tioga_Pass_MB.brd

CT62  CAP  1000PF 50V 10% X7R  pkg 0402LF  page 214 : A = VR_PVCCIO_CPU1_PH1_SW ; B = VR_PVCCIO_CPU1_PH1_SW_RC
R1D46  RES  10.0 1% CHIP  pkg 0402  page 200 : A = P12V_HSC_SENP0 ; B = A_HSC_HSP
R1E3  RES  100.0 1% CHIP  pkg 0603  page 208 : A = PVCCIN_CPU1 ; B = GND

(kicad_pcb
	(version 20260206)
	(generator "pcbnew")
	(generator_version "10.0")
	(general
		(thickness 1.6)
		(legacy_teardrops no)
	)
	(paper "A4")
	(title_block
		(title "Wiwynn_Tioga_Pass_MB.brd")
		(comment 1 "Tioga Pass / footprints 160-162 of 4770")
	)
	(layers
		(0 "F.Cu" signal "TOP")
		(4 "In1.Cu" signal "L2GND")
		(6 "In2.Cu" signal "L3")
		(8 "In3.Cu" signal "L4GND")
		(10 "In4.Cu" signal "L5")
		(12 "In5.Cu" signal "L6GND")
		(14 "In6.Cu" signal "L7VCC")
		(16 "In7.Cu" signal "L8VCC")
		(18 "In8.Cu" signal "L9GND")
		(20 "In9.Cu" signal "L10")
		(22 "In10.Cu" signal "L11GND")
		(24 "In11.Cu" signal "L12")
		(26 "In12.Cu" signal "L13GND")
		(2 "B.Cu" signal "BOTTOM")
		(9 "F.Adhes" user "F.Adhesive")
		(11 "B.Adhes" user "B.Adhesive")
		(13 "F.Paste" user "Package Geometry/Pastemask Top")
		(15 "B.Paste" user "Package Geometry/Pastemask Bottom")
		(5 "F.SilkS" user "Ref Des/Silkscreen Top")
		(7 "B.SilkS" user "Ref Des/Silkscreen Bottom")
		(1 "F.Mask" user "Board Geometry/Soldermask Top")
		(3 "B.Mask" user "Board Geometry/Soldermask Bottom")
		(17 "Dwgs.User" user "User.Drawings")
		(19 "Cmts.User" user "User.Comments")
		(21 "Eco1.User" user "User.Eco1")
		(23 "Eco2.User" user "User.Eco2")
		(25 "Edge.Cuts" user "Board Geometry/Outline")
		(27 "Margin" user)
		(31 "F.CrtYd" user "Package Geometry/Place Bound Top")
		(29 "B.CrtYd" user "Package Geometry/Place Bound Bottom")
		(35 "F.Fab" user "Ref Des/Assembly Top")
		(33 "B.Fab" user "Ref Des/Assembly Bottom")
	)
	(footprint ""
		(layer "F.Cu")
		(at 170.234102 -57.812686 90)
		(property "Reference" "CT62"
			(at -0.8382 -0.67818 90)
			(unlocked yes)
			(layer "F.SilkS")
			(effects
				(font
					(size 0.4064 0.254)
					(thickness 0.1524)
				)
				(justify left)
			)
		)
		(property "Value" ""
			(at 0 0 90)
			(layer "F.Fab")
			(effects
				(font
					(size 1.27 1.27)
				)
			)
		)
		(duplicate_pad_numbers_are_jumpers no)
		(fp_poly
			(pts
				(xy 0.3048 -0.1016) (xy 0.3048 0.9906) (xy -0.3048 0.9906) (xy -0.3048 -0.1016)
			)
			(stroke
				(width 0)
				(type default)
			)
			(fill no)
			(layer "F.CrtYd")
		)
		(fp_line
			(start 0.3048 -0.1016)
			(end -0.3048 -0.1016)
			(stroke
				(width 0.1)
				(type default)
			)
			(layer "F.Fab")
		)
		(fp_line
			(start -0.3048 -0.1016)
			(end -0.3048 0.9906)
			(stroke
				(width 0.1)
				(type default)
			)
			(layer "F.Fab")
		)
		(fp_line
			(start 0.3048 0.9906)
			(end 0.3048 -0.1016)
			(stroke
				(width 0.1)
				(type default)
			)
			(layer "F.Fab")
		)
		(fp_line
			(start -0.3048 0.9906)
			(end 0.3048 0.9906)
			(stroke
				(width 0.1)
				(type default)
			)
			(layer "F.Fab")
		)
		(pad "1" smd rect
			(at 0 0 90)
			(size 0.508 0.508)
			(layers "F.Cu" "F.Mask" "F.Paste")
			(net "VR_PVCCIO_CPU1_PH1_SW")
		)
		(pad "2" smd rect
			(at 0 0.889 90)
			(size 0.508 0.508)
			(layers "F.Cu" "F.Mask" "F.Paste")
			(net "VR_PVCCIO_CPU1_PH1_SW_RC")
		)
		(zone
			(layer "F.Cu")
			(hatch none 0.5)
			(connect_pads
				(clearance 0)
			)
			(min_thickness 0.25)
			(keepout
				(tracks allowed)
				(vias not_allowed)
				(pads allowed)
				(copperpour not_allowed)
				(footprints allowed)
			)
			(placement
				(enabled no)
				(sheetname "")
			)
			(fill
				(thermal_gap 0.5)
				(thermal_bridge_width 0.5)
				(island_removal_mode 0)
			)
			(polygon
				(pts
					(xy 170.488102 -57.558686) (xy 170.488102 -58.066686) (xy 170.869102 -58.066686) (xy 170.869102 -57.558686)
				)
			)
		)
		(zone
			(layer "F.Cu")
			(hatch none 0.5)
			(connect_pads
				(clearance 0)
			)
			(min_thickness 0.25)
			(keepout
				(tracks not_allowed)
				(vias allowed)
				(pads allowed)
				(copperpour not_allowed)
				(footprints allowed)
			)
			(placement
				(enabled no)
				(sheetname "")
			)
			(fill
				(thermal_gap 0.5)
				(thermal_bridge_width 0.5)
				(island_removal_mode 0)
			)
			(polygon
				(pts
					(xy 170.869102 -57.558686) (xy 170.869102 -58.066686) (xy 170.488102 -58.066686) (xy 170.488102 -57.558686)
				)
			)
		)
	)
	(footprint ""
		(layer "F.Cu")
		(at 44.1198 -52.79898 -90)
		(property "Reference" "R1E3"
			(at 0 0 270)
			(layer "F.SilkS")
			(hide yes)
			(effects
				(font
					(size 1.27 1.27)
				)
			)
		)
		(property "Value" ""
			(at 0 0 270)
			(layer "F.Fab")
			(effects
				(font
					(size 1.27 1.27)
				)
			)
		)
		(duplicate_pad_numbers_are_jumpers no)
		(fp_poly
			(pts
				(xy -0.4953 -0.2032) (xy 0.4953 -0.2032) (xy 0.4953 1.6002) (xy -0.4953 1.6002)
			)
			(stroke
				(width 0)
				(type default)
			)
			(fill no)
			(layer "F.CrtYd")
		)
		(fp_line
			(start -0.4953 1.6002)
			(end -0.4953 -0.2032)
			(stroke
				(width 0.1)
				(type default)
			)
			(layer "F.Fab")
		)
		(fp_line
			(start 0.4953 1.6002)
			(end -0.4953 1.6002)
			(stroke
				(width 0.1)
				(type default)
			)
			(layer "F.Fab")
		)
		(fp_line
			(start -0.4953 -0.2032)
			(end 0.4953 -0.2032)
			(stroke
				(width 0.1)
				(type default)
			)
			(layer "F.Fab")
		)
		(fp_line
			(start 0.4953 -0.2032)
			(end 0.4953 1.6002)
			(stroke
				(width 0.1)
				(type default)
			)
			(layer "F.Fab")
		)
		(pad "1" smd rect
			(at 0 0 270)
			(size 0.762 0.889)
			(layers "F.Cu" "F.Mask" "F.Paste")
			(net "PVCCIN_CPU1")
		)
		(pad "2" smd rect
			(at 0 1.397 270)
			(size 0.762 0.889)
			(layers "F.Cu" "F.Mask" "F.Paste")
			(net "GND")
		)
		(zone
			(layer "F.Cu")
			(hatch none 0.5)
			(connect_pads
				(clearance 0)
			)
			(min_thickness 0.25)
			(keepout
				(tracks not_allowed)
				(vias allowed)
				(pads allowed)
				(copperpour not_allowed)
				(footprints allowed)
			)
			(placement
				(enabled no)
				(sheetname "")
			)
			(fill
				(thermal_gap 0.5)
				(thermal_bridge_width 0.5)
				(island_removal_mode 0)
			)
			(polygon
				(pts
					(xy 43.1673 -53.17998) (xy 43.1673 -52.41798) (xy 43.6753 -52.41798) (xy 43.6753 -53.17998)
				)
			)
		)
		(zone
			(layer "F.Cu")
			(hatch none 0.5)
			(connect_pads
				(clearance 0)
			)
			(min_thickness 0.25)
			(keepout
				(tracks allowed)
				(vias not_allowed)
				(pads allowed)
				(copperpour not_allowed)
				(footprints allowed)
			)
			(placement
				(enabled no)
				(sheetname "")
			)
			(fill
				(thermal_gap 0.5)
				(thermal_bridge_width 0.5)
				(island_removal_mode 0)
			)
			(polygon
				(pts
					(xy 43.1673 -52.41798) (xy 43.6753 -52.41798) (xy 43.6753 -53.17998) (xy 43.1673 -53.17998)
				)
			)
		)
	)
	(footprint ""
		(layer "F.Cu")
		(at 9.398 -68.0593 180)
		(property "Reference" "R1D46"
			(at 0 0 180)
			(layer "F.SilkS")
			(hide yes)
			(effects
				(font
					(size 1.27 1.27)
				)
			)
		)
		(property "Value" ""
			(at 0 0 180)
			(layer "F.Fab")
			(effects
				(font
					(size 1.27 1.27)
				)
			)
		)
		(duplicate_pad_numbers_are_jumpers no)
		(fp_rect
			(start 0.2794 0.9906)
			(end -0.2794 -0.1016)
			(stroke
				(width 0)
				(type default)
			)
			(fill no)
			(layer "F.CrtYd")
		)
		(fp_line
			(start 0.2794 0.9906)
			(end 0.2794 -0.1016)
			(stroke
				(width 0.1)
				(type default)
			)
			(layer "F.Fab")
		)
		(fp_line
			(start 0.2794 -0.1016)
			(end -0.2794 -0.1016)
			(stroke
				(width 0.1)
				(type default)
			)
			(layer "F.Fab")
		)
		(fp_line
			(start -0.2794 0.9906)
			(end 0.2794 0.9906)
			(stroke
				(width 0.1)
				(type default)
			)
			(layer "F.Fab")
		)
		(fp_line
			(start -0.2794 -0.1016)
			(end -0.2794 0.9906)
			(stroke
				(width 0.1)
				(type default)
			)
			(layer "F.Fab")
		)
		(pad "1" smd rect
			(at 0 0 180)
			(size 0.508 0.508)
			(layers "F.Cu" "F.Mask" "F.Paste")
			(net "P12V_HSC_SENP0")
		)
		(pad "2" smd rect
			(at 0 0.889 180)
			(size 0.508 0.508)
			(layers "F.Cu" "F.Mask" "F.Paste")
			(net "A_HSC_HSP")
		)
		(zone
			(layer "F.Cu")
			(hatch none 0.5)
			(connect_pads
				(clearance 0)
			)
			(min_thickness 0.25)
			(keepout
				(tracks not_allowed)
				(vias allowed)
				(pads allowed)
				(copperpour not_allowed)
				(footprints allowed)
			)
			(placement
				(enabled no)
				(sheetname "")
			)
			(fill
				(thermal_gap 0.5)
				(thermal_bridge_width 0.5)
				(island_removal_mode 0)
			)
			(polygon
				(pts
					(xy 9.144 -68.6943) (xy 9.144 -68.3133) (xy 9.652 -68.3133) (xy 9.652 -68.6943)
				)
			)
		)
		(zone
			(layer "F.Cu")
			(hatch none 0.5)
			(connect_pads
				(clearance 0)
			)
			(min_thickness 0.25)
			(keepout
				(tracks allowed)
				(vias not_allowed)
				(pads allowed)
				(copperpour not_allowed)
				(footprints allowed)
			)
			(placement
				(enabled no)
				(sheetname "")
			)
			(fill
				(thermal_gap 0.5)
				(thermal_bridge_width 0.5)
				(island_removal_mode 0)
			)
			(polygon
				(pts
					(xy 9.144 -68.6943) (xy 9.144 -68.3133) (xy 9.652 -68.3133) (xy 9.652 -68.6943)
				)
			)
		)
	)
)
